# T6G (Grand Teton) — schematic netlist excerpt (pin names and nets, part order shuffled) for the footprints in the layout excerpt that follows; sources: Cadence DE-HDL packaged netlist, KiCad conversion of 04192023_DAF0TMB3IC0_F0TG_MB_C_brd_V02_OCP.brd

R1196  Q_RES  0 5% EMPTY  pkg 0402LF  page 141 : A = HP_LVC3_OCP_V3_2_P12V_PWRGD ; B = P3V3_OCP_EN_2
C148  Q_CAP  0.1UF 25V 10% X7R  pkg 0402  page 101 : A = P3V3_AUX ; B = GND
R787  Q_RES  4.7K 5% CHIP  pkg 0201LF  page 331 : A = TEST1_RT_CPU1_P1 ; B = GND

(kicad_pcb
	(version 20260206)
	(generator "pcbnew")
	(generator_version "10.0")
	(general
		(thickness 1.6)
		(legacy_teardrops no)
	)
	(paper "A4")
	(title_block
		(title "04192023_DAF0TMB3IC0_F0TG_MB_C_brd_V02_OCP.brd")
		(comment 1 "Grand Teton / footprints 8048-8050 of 8354")
	)
	(layers
		(0 "F.Cu" signal "TOP")
		(4 "In1.Cu" signal "GND")
		(6 "In2.Cu" signal "IN1")
		(8 "In3.Cu" signal "GND1")
		(10 "In4.Cu" signal "IN2")
		(12 "In5.Cu" signal "GND2")
		(14 "In6.Cu" signal "IN3")
		(16 "In7.Cu" signal "GND3")
		(18 "In8.Cu" signal "VCC")
		(20 "In9.Cu" signal "VCC1")
		(22 "In10.Cu" signal "GND4")
		(24 "In11.Cu" signal "IN4")
		(26 "In12.Cu" signal "GND5")
		(28 "In13.Cu" signal "IN5")
		(30 "In14.Cu" signal "GND6")
		(32 "In15.Cu" signal "IN6")
		(34 "In16.Cu" signal "GND7")
		(2 "B.Cu" signal "BOTTOM")
		(9 "F.Adhes" user "F.Adhesive")
		(11 "B.Adhes" user "B.Adhesive")
		(13 "F.Paste" user "Package Geometry/Pastemask Top")
		(15 "B.Paste" user "Package Geometry/Pastemask Bottom")
		(5 "F.SilkS" user "Ref Des/Silkscreen Top")
		(7 "B.SilkS" user "Ref Des/Silkscreen Bottom")
		(1 "F.Mask" user "Board Geometry/Soldermask Top")
		(3 "B.Mask" user "Board Geometry/Soldermask Bottom")
		(17 "Dwgs.User" user "User.Drawings")
		(19 "Cmts.User" user "User.Comments")
		(21 "Eco1.User" user "User.Eco1")
		(23 "Eco2.User" user "User.Eco2")
		(25 "Edge.Cuts" user "Board Geometry/Outline")
		(27 "Margin" user)
		(31 "F.CrtYd" user "Package Geometry/Place Bound Top")
		(29 "B.CrtYd" user "Package Geometry/Place Bound Bottom")
		(35 "F.Fab" user "Ref Des/Assembly Top")
		(33 "B.Fab" user "Ref Des/Assembly Bottom")
	)
	(footprint ""
		(layer "B.Cu")
		(at 63.194438 -28.382722)
		(property "Reference" "R1196"
			(at 0 0 0)
			(layer "B.SilkS")
			(hide yes)
			(effects
				(font
					(size 1.27 1.27)
				)
				(justify mirror)
			)
		)
		(property "Value" ""
			(at 0 0 0)
			(layer "B.Fab")
			(effects
				(font
					(size 1.27 1.27)
				)
				(justify mirror)
			)
		)
		(duplicate_pad_numbers_are_jumpers no)
		(fp_line
			(start -0.7874 -0.4064)
			(end -0.7874 0.4064)
			(stroke
				(width 0.1524)
				(type default)
			)
			(layer "B.SilkS")
		)
		(fp_line
			(start -0.7874 0.4064)
			(end 0.7874 0.4064)
			(stroke
				(width 0.1524)
				(type default)
			)
			(layer "B.SilkS")
		)
		(fp_line
			(start 0.7874 -0.4064)
			(end -0.7874 -0.4064)
			(stroke
				(width 0.1524)
				(type default)
			)
			(layer "B.SilkS")
		)
		(fp_line
			(start 0.7874 0.4064)
			(end 0.7874 -0.4064)
			(stroke
				(width 0.1524)
				(type default)
			)
			(layer "B.SilkS")
		)
		(fp_line
			(start -0.67945 -0.3048)
			(end -0.67945 0.3048)
			(stroke
				(width 0.1)
				(type default)
			)
			(layer "B.Fab")
		)
		(fp_line
			(start -0.67945 0.3048)
			(end -0.120396 0.3048)
			(stroke
				(width 0.1)
				(type default)
			)
			(layer "B.Fab")
		)
		(fp_line
			(start -0.12065 -0.3048)
			(end -0.67945 -0.3048)
			(stroke
				(width 0.1)
				(type default)
			)
			(layer "B.Fab")
		)
		(fp_line
			(start -0.12065 -0.2794)
			(end -0.12065 -0.3048)
			(stroke
				(width 0.1)
				(type default)
			)
			(layer "B.Fab")
		)
		(fp_line
			(start -0.120396 0.2794)
			(end 0.12065 0.2794)
			(stroke
				(width 0.1)
				(type default)
			)
			(layer "B.Fab")
		)
		(fp_line
			(start -0.120396 0.3048)
			(end -0.120396 0.2794)
			(stroke
				(width 0.1)
				(type default)
			)
			(layer "B.Fab")
		)
		(fp_line
			(start 0.12065 -0.305054)
			(end 0.12065 -0.2794)
			(stroke
				(width 0.1)
				(type default)
			)
			(layer "B.Fab")
		)
		(fp_line
			(start 0.12065 -0.2794)
			(end -0.12065 -0.2794)
			(stroke
				(width 0.1)
				(type default)
			)
			(layer "B.Fab")
		)
		(fp_line
			(start 0.12065 0.2794)
			(end 0.12065 0.3048)
			(stroke
				(width 0.1)
				(type default)
			)
			(layer "B.Fab")
		)
		(fp_line
			(start 0.12065 0.3048)
			(end 0.67945 0.3048)
			(stroke
				(width 0.1)
				(type default)
			)
			(layer "B.Fab")
		)
		(fp_line
			(start 0.67945 -0.305054)
			(end 0.12065 -0.305054)
			(stroke
				(width 0.1)
				(type default)
			)
			(layer "B.Fab")
		)
		(fp_line
			(start 0.67945 0.3048)
			(end 0.67945 -0.305054)
			(stroke
				(width 0.1)
				(type default)
			)
			(layer "B.Fab")
		)
		(pad "1" smd circle
			(at 0.40005 0 180)
			(size 0 0)
			(layers "B.Cu" "B.Mask" "B.Paste")
			(net "HP_LVC3_OCP_V3_2_P12V_PWRGD")
		)
		(pad "2" smd circle
			(at -0.40005 0 180)
			(size 0 0)
			(layers "B.Cu" "B.Mask" "B.Paste")
			(net "P3V3_OCP_EN_2")
		)
	)
	(footprint ""
		(layer "B.Cu")
		(at 75.7936 -384.66268 180)
		(property "Reference" "R787"
			(at 0 0 0)
			(layer "B.SilkS")
			(hide yes)
			(effects
				(font
					(size 1.27 1.27)
				)
				(justify mirror)
			)
		)
		(property "Value" ""
			(at 0 0 0)
			(layer "B.Fab")
			(effects
				(font
					(size 1.27 1.27)
				)
				(justify mirror)
			)
		)
		(duplicate_pad_numbers_are_jumpers no)
		(fp_line
			(start 0.32512 0.175006)
			(end 0.32512 -0.175006)
			(stroke
				(width 0.1)
				(type default)
			)
			(layer "B.Fab")
		)
		(fp_line
			(start 0.32512 -0.175006)
			(end -0.32512 -0.175006)
			(stroke
				(width 0.1)
				(type default)
			)
			(layer "B.Fab")
		)
		(fp_line
			(start -0.32512 0.175006)
			(end 0.32512 0.175006)
			(stroke
				(width 0.1)
				(type default)
			)
			(layer "B.Fab")
		)
		(fp_line
			(start -0.32512 -0.175006)
			(end -0.32512 0.175006)
			(stroke
				(width 0.1)
				(type default)
			)
			(layer "B.Fab")
		)
		(pad "1" smd rect
			(at 0.2667 0)
			(size 0.3048 0.381)
			(layers "B.Cu" "B.Mask" "B.Paste")
			(net "TEST1_RT_CPU1_P1")
		)
		(pad "2" smd rect
			(at -0.2667 0 180)
			(size 0.3048 0.381)
			(layers "B.Cu" "B.Mask" "B.Paste")
			(net "GND")
		)
	)
	(footprint ""
		(layer "B.Cu")
		(at 36.040568 -193.9798)
		(property "Reference" "C148"
			(at 0 0 0)
			(layer "B.SilkS")
			(hide yes)
			(effects
				(font
					(size 1.27 1.27)
				)
				(justify mirror)
			)
		)
		(property "Value" ""
			(at 0 0 0)
			(layer "B.Fab")
			(effects
				(font
					(size 1.27 1.27)
				)
				(justify mirror)
			)
		)
		(duplicate_pad_numbers_are_jumpers no)
		(fp_line
			(start -0.7874 -0.4064)
			(end -0.7874 0.4064)
			(stroke
				(width 0.1524)
				(type default)
			)
			(layer "B.SilkS")
		)
		(fp_line
			(start -0.7874 0.4064)
			(end 0.7874 0.4064)
			(stroke
				(width 0.1524)
				(type default)
			)
			(layer "B.SilkS")
		)
		(fp_line
			(start 0.7874 -0.4064)
			(end -0.7874 -0.4064)
			(stroke
				(width 0.1524)
				(type default)
			)
			(layer "B.SilkS")
		)
		(fp_line
			(start 0.7874 0.4064)
			(end 0.7874 -0.4064)
			(stroke
				(width 0.1524)
				(type default)
			)
			(layer "B.SilkS")
		)
		(fp_line
			(start -0.67945 -0.3048)
			(end -0.67945 0.3048)
			(stroke
				(width 0.1)
				(type default)
			)
			(layer "B.Fab")
		)
		(fp_line
			(start -0.67945 0.3048)
			(end -0.120396 0.3048)
			(stroke
				(width 0.1)
				(type default)
			)
			(layer "B.Fab")
		)
		(fp_line
			(start -0.12065 -0.3048)
			(end -0.67945 -0.3048)
			(stroke
				(width 0.1)
				(type default)
			)
			(layer "B.Fab")
		)
		(fp_line
			(start -0.12065 -0.2794)
			(end -0.12065 -0.3048)
			(stroke
				(width 0.1)
				(type default)
			)
			(layer "B.Fab")
		)
		(fp_line
			(start -0.120396 0.2794)
			(end 0.12065 0.2794)
			(stroke
				(width 0.1)
				(type default)
			)
			(layer "B.Fab")
		)
		(fp_line
			(start -0.120396 0.3048)
			(end -0.120396 0.2794)
			(stroke
				(width 0.1)
				(type default)
			)
			(layer "B.Fab")
		)
		(fp_line
			(start 0.12065 -0.305054)
			(end 0.12065 -0.2794)
			(stroke
				(width 0.1)
				(type default)
			)
			(layer "B.Fab")
		)
		(fp_line
			(start 0.12065 -0.2794)
			(end -0.12065 -0.2794)
			(stroke
				(width 0.1)
				(type default)
			)
			(layer "B.Fab")
		)
		(fp_line
			(start 0.12065 0.2794)
			(end 0.12065 0.3048)
			(stroke
				(width 0.1)
				(type default)
			)
			(layer "B.Fab")
		)
		(fp_line
			(start 0.12065 0.3048)
			(end 0.67945 0.3048)
			(stroke
				(width 0.1)
				(type default)
			)
			(layer "B.Fab")
		)
		(fp_line
			(start 0.67945 -0.305054)
			(end 0.12065 -0.305054)
			(stroke
				(width 0.1)
				(type default)
			)
			(layer "B.Fab")
		)
		(fp_line
			(start 0.67945 0.3048)
			(end 0.67945 -0.305054)
			(stroke
				(width 0.1)
				(type default)
			)
			(layer "B.Fab")
		)
		(pad "1" smd circle
			(at 0.40005 0 180)
			(size 0 0)
			(layers "B.Cu" "B.Mask" "B.Paste")
			(net "P3V3_AUX")
		)
		(pad "2" smd circle
			(at -0.40005 0 180)
			(size 0 0)
			(layers "B.Cu" "B.Mask" "B.Paste")
			(net "GND")
		)
	)
)
